(kicad_pcb
	(version 20260206)
	(generator "pcbnew")
	(generator_version "10.0")
	(general
		(thickness 1.6)
		(legacy_teardrops no)
	)
	(paper "A4")
	(title_block
		(title "01162023_DA0F0TEBIF0_F0T_Expander_BD_F_brd_V02_OCP.brd")
		(comment 1 "Grand Teton / footprints 6371-6376 of 9728")
	)
	(layers
		(0 "F.Cu" signal "TOP")
		(4 "In1.Cu" signal "GND")
		(6 "In2.Cu" signal "VCC")
		(8 "In3.Cu" signal "VCC1")
		(10 "In4.Cu" signal "GND1")
		(12 "In5.Cu" signal "IN1")
		(14 "In6.Cu" signal "GND2")
		(16 "In7.Cu" signal "IN2")
		(18 "In8.Cu" signal "GND3")
		(20 "In9.Cu" signal "IN3")
		(22 "In10.Cu" signal "GND4")
		(24 "In11.Cu" signal "IN4")
		(26 "In12.Cu" signal "GND5")
		(28 "In13.Cu" signal "IN5")
		(30 "In14.Cu" signal "GND6")
		(32 "In15.Cu" signal "IN6")
		(34 "In16.Cu" signal "GND7")
		(2 "B.Cu" signal "BOTTOM")
		(9 "F.Adhes" user "F.Adhesive")
		(11 "B.Adhes" user "B.Adhesive")
		(13 "F.Paste" user "Package Geometry/Pastemask Top")
		(15 "B.Paste" user "Package Geometry/Pastemask Bottom")
		(5 "F.SilkS" user "Ref Des/Silkscreen Top")
		(7 "B.SilkS" user "Ref Des/Silkscreen Bottom")
		(1 "F.Mask" user "Board Geometry/Soldermask Top")
		(3 "B.Mask" user "Board Geometry/Soldermask Bottom")
		(17 "Dwgs.User" user "User.Drawings")
		(19 "Cmts.User" user "User.Comments")
		(21 "Eco1.User" user "User.Eco1")
		(23 "Eco2.User" user "User.Eco2")
		(25 "Edge.Cuts" user "Board Geometry/Outline")
		(27 "Margin" user)
		(31 "F.CrtYd" user "Package Geometry/Place Bound Top")
		(29 "B.CrtYd" user "Package Geometry/Place Bound Bottom")
		(35 "F.Fab" user "Ref Des/Assembly Top")
		(33 "B.Fab" user "Ref Des/Assembly Bottom")
	)
	(footprint ""
		(layer "F.Cu")
		(at 450.195188 -415.621216 90)
		(property "Reference" "R5601"
			(at 0 0 90)
			(layer "F.SilkS")
			(hide yes)
			(effects
				(font
					(size 1.27 1.27)
				)
			)
		)
		(property "Value" ""
			(at 0 0 90)
			(layer "F.Fab")
			(effects
				(font
					(size 1.27 1.27)
				)
			)
		)
		(duplicate_pad_numbers_are_jumpers no)
		(fp_line
			(start 0.7874 -0.4064)
			(end 0.7874 0.4064)
			(stroke
				(width 0.1524)
				(type default)
			)
			(layer "F.SilkS")
		)
		(fp_line
			(start -0.7874 -0.4064)
			(end 0.7874 -0.4064)
			(stroke
				(width 0.1524)
				(type default)
			)
			(layer "F.SilkS")
		)
		(fp_line
			(start 0.7874 0.4064)
			(end -0.7874 0.4064)
			(stroke
				(width 0.1524)
				(type default)
			)
			(layer "F.SilkS")
		)
		(fp_line
			(start -0.7874 0.4064)
			(end -0.7874 -0.4064)
			(stroke
				(width 0.1524)
				(type default)
			)
			(layer "F.SilkS")
		)
		(fp_line
			(start -0.12065 -0.305054)
			(end -0.12065 -0.2794)
			(stroke
				(width 0.1)
				(type default)
			)
			(layer "F.Fab")
		)
		(fp_line
			(start -0.67945 -0.305054)
			(end -0.12065 -0.305054)
			(stroke
				(width 0.1)
				(type default)
			)
			(layer "F.Fab")
		)
		(fp_line
			(start 0.67945 -0.3048)
			(end 0.67945 0.3048)
			(stroke
				(width 0.1)
				(type default)
			)
			(layer "F.Fab")
		)
		(fp_line
			(start 0.12065 -0.3048)
			(end 0.67945 -0.3048)
			(stroke
				(width 0.1)
				(type default)
			)
			(layer "F.Fab")
		)
		(fp_line
			(start 0.12065 -0.2794)
			(end 0.12065 -0.3048)
			(stroke
				(width 0.1)
				(type default)
			)
			(layer "F.Fab")
		)
		(fp_line
			(start -0.12065 -0.2794)
			(end 0.12065 -0.2794)
			(stroke
				(width 0.1)
				(type default)
			)
			(layer "F.Fab")
		)
		(fp_line
			(start 0.120396 0.2794)
			(end -0.12065 0.2794)
			(stroke
				(width 0.1)
				(type default)
			)
			(layer "F.Fab")
		)
		(fp_line
			(start -0.12065 0.2794)
			(end -0.12065 0.3048)
			(stroke
				(width 0.1)
				(type default)
			)
			(layer "F.Fab")
		)
		(fp_line
			(start 0.67945 0.3048)
			(end 0.120396 0.3048)
			(stroke
				(width 0.1)
				(type default)
			)
			(layer "F.Fab")
		)
		(fp_line
			(start 0.120396 0.3048)
			(end 0.120396 0.2794)
			(stroke
				(width 0.1)
				(type default)
			)
			(layer "F.Fab")
		)
		(fp_line
			(start -0.12065 0.3048)
			(end -0.67945 0.3048)
			(stroke
				(width 0.1)
				(type default)
			)
			(layer "F.Fab")
		)
		(fp_line
			(start -0.67945 0.3048)
			(end -0.67945 -0.305054)
			(stroke
				(width 0.1)
				(type default)
			)
			(layer "F.Fab")
		)
		(pad "1" smd circle
			(at -0.40005 0 90)
			(size 0 0)
			(layers "F.Cu" "F.Mask" "F.Paste")
			(net "LM75_1_A2")
		)
		(pad "2" smd circle
			(at 0.40005 0 90)
			(size 0 0)
			(layers "F.Cu" "F.Mask" "F.Paste")
			(net "P3V3_AUX")
		)
	)
	(footprint ""
		(layer "F.Cu")
		(at 455.32929 -105.253536)
		(property "Reference" "PD17"
			(at 4.988052 0.267208 0)
			(unlocked yes)
			(layer "F.SilkS")
			(effects
				(font
					(size 0.7874 0.5842)
					(thickness 0.1524)
				)
				(justify left)
			)
		)
		(property "Value" ""
			(at 0 0 0)
			(layer "F.Fab")
			(effects
				(font
					(size 1.27 1.27)
				)
			)
		)
		(duplicate_pad_numbers_are_jumpers no)
		(fp_line
			(start -3.656584 -1.970024)
			(end -3.656584 1.970024)
			(stroke
				(width 0.1524)
				(type default)
			)
			(layer "F.SilkS")
		)
		(fp_line
			(start -3.656584 1.970024)
			(end 4.240784 1.970024)
			(stroke
				(width 0.1524)
				(type default)
			)
			(layer "F.SilkS")
		)
		(fp_line
			(start 4.240784 -1.970024)
			(end -3.656584 -1.970024)
			(stroke
				(width 0.1524)
				(type default)
			)
			(layer "F.SilkS")
		)
		(fp_line
			(start 4.240784 1.970024)
			(end 4.240784 -1.970024)
			(stroke
				(width 0.1524)
				(type default)
			)
			(layer "F.SilkS")
		)
		(fp_rect
			(start 3.580384 1.970024)
			(end 4.240784 -1.970024)
			(stroke
				(width 0)
				(type default)
			)
			(fill yes)
			(layer "F.SilkS")
		)
		(fp_line
			(start -2.3749 -1.970024)
			(end -2.3749 1.970024)
			(stroke
				(width 0.1)
				(type default)
			)
			(layer "F.Fab")
		)
		(fp_line
			(start -2.3749 1.970024)
			(end 2.3749 1.970024)
			(stroke
				(width 0.1)
				(type default)
			)
			(layer "F.Fab")
		)
		(fp_line
			(start 2.3749 -1.970024)
			(end -2.3749 -1.970024)
			(stroke
				(width 0.1)
				(type default)
			)
			(layer "F.Fab")
		)
		(fp_line
			(start 2.3749 1.970024)
			(end 2.3749 -1.970024)
			(stroke
				(width 0.1)
				(type default)
			)
			(layer "F.Fab")
		)
		(fp_text user "+"
			(at -4.9784 -0.23495 0)
			(unlocked yes)
			(layer "F.Fab")
			(effects
				(font
					(size 1.905 1.4224)
					(thickness 0.1524)
				)
				(justify left)
			)
		)
		(fp_text user "-"
			(at 4.1656 -0.23495 0)
			(unlocked yes)
			(layer "F.Fab")
			(effects
				(font
					(size 1.905 1.4224)
					(thickness 0.1524)
				)
				(justify left)
			)
		)
		(pad "A" smd rect
			(at -2.450084 0)
			(size 2.159 2.2606)
			(layers "F.Cu" "F.Mask" "F.Paste")
			(net "GND")
		)
		(pad "C" smd rect
			(at 2.450084 0)
			(size 2.159 2.2606)
			(layers "F.Cu" "F.Mask" "F.Paste")
			(net "P12V_AUX")
		)
	)
	(footprint ""
		(layer "F.Cu")
		(at 116.672106 -316.869318)
		(property "Reference" "C1157"
			(at 0 0 0)
			(layer "F.SilkS")
			(hide yes)
			(effects
				(font
					(size 1.27 1.27)
				)
			)
		)
		(property "Value" ""
			(at 0 0 0)
			(layer "F.Fab")
			(effects
				(font
					(size 1.27 1.27)
				)
			)
		)
		(duplicate_pad_numbers_are_jumpers no)
		(fp_line
			(start -1.2954 -0.5842)
			(end 1.2954 -0.5842)
			(stroke
				(width 0.1524)
				(type default)
			)
			(layer "F.SilkS")
		)
		(fp_line
			(start -1.2954 0.5842)
			(end -1.2954 -0.5842)
			(stroke
				(width 0.1524)
				(type default)
			)
			(layer "F.SilkS")
		)
		(fp_line
			(start 1.2954 -0.5842)
			(end 1.2954 0.5842)
			(stroke
				(width 0.1524)
				(type default)
			)
			(layer "F.SilkS")
		)
		(fp_line
			(start 1.2954 0.5842)
			(end -1.2954 0.5842)
			(stroke
				(width 0.1524)
				(type default)
			)
			(layer "F.SilkS")
		)
		(fp_line
			(start -1.1938 -0.4064)
			(end -0.8636 -0.4064)
			(stroke
				(width 0.1)
				(type default)
			)
			(layer "F.Fab")
		)
		(fp_line
			(start -1.1938 0.4064)
			(end -1.1938 -0.4064)
			(stroke
				(width 0.1)
				(type default)
			)
			(layer "F.Fab")
		)
		(fp_line
			(start -0.8636 -0.4572)
			(end 0.8636 -0.4572)
			(stroke
				(width 0.1)
				(type default)
			)
			(layer "F.Fab")
		)
		(fp_line
			(start -0.8636 -0.4064)
			(end -0.8636 -0.4572)
			(stroke
				(width 0.1)
				(type default)
			)
			(layer "F.Fab")
		)
		(fp_line
			(start -0.8636 0.4064)
			(end -1.1938 0.4064)
			(stroke
				(width 0.1)
				(type default)
			)
			(layer "F.Fab")
		)
		(fp_line
			(start -0.8636 0.4572)
			(end -0.8636 0.4064)
			(stroke
				(width 0.1)
				(type default)
			)
			(layer "F.Fab")
		)
		(fp_line
			(start 0.8636 -0.4572)
			(end 0.8636 -0.4064)
			(stroke
				(width 0.1)
				(type default)
			)
			(layer "F.Fab")
		)
		(fp_line
			(start 0.8636 -0.4064)
			(end 1.1938 -0.4064)
			(stroke
				(width 0.1)
				(type default)
			)
			(layer "F.Fab")
		)
		(fp_line
			(start 0.8636 0.4064)
			(end 0.8636 0.4572)
			(stroke
				(width 0.1)
				(type default)
			)
			(layer "F.Fab")
		)
		(fp_line
			(start 0.8636 0.4572)
			(end -0.8636 0.4572)
			(stroke
				(width 0.1)
				(type default)
			)
			(layer "F.Fab")
		)
		(fp_line
			(start 1.1938 -0.4064)
			(end 1.1938 0.4064)
			(stroke
				(width 0.1)
				(type default)
			)
			(layer "F.Fab")
		)
		(fp_line
			(start 1.1938 0.4064)
			(end 0.8636 0.4064)
			(stroke
				(width 0.1)
				(type default)
			)
			(layer "F.Fab")
		)
		(pad "1" smd rect
			(at -0.7366 0 270)
			(size 0.7112 0.8128)
			(layers "F.Cu" "F.Mask" "F.Paste")
			(net "P0V8_SERDES_VDDA_PEX0")
		)
		(pad "2" smd rect
			(at 0.7366 0 270)
			(size 0.7112 0.8128)
			(layers "F.Cu" "F.Mask" "F.Paste")
			(net "GND")
		)
	)
	(footprint ""
		(layer "F.Cu")
		(at 439.924698 -115.835176 90)
		(property "Reference" "PU122"
			(at 0.009398 -4.915154 90)
			(unlocked yes)
			(layer "F.SilkS")
			(effects
				(font
					(size 0.7874 0.5842)
					(thickness 0.1524)
				)
			)
		)
		(property "Value" ""
			(at 0 0 90)
			(layer "F.Fab")
			(effects
				(font
					(size 1.27 1.27)
				)
			)
		)
		(duplicate_pad_numbers_are_jumpers no)
		(fp_line
			(start 1.239774 -1.495298)
			(end 1.239774 1.495298)
			(stroke
				(width 0.1524)
				(type default)
			)
			(layer "F.SilkS")
		)
		(fp_line
			(start -1.239774 -1.495298)
			(end 1.239774 -1.495298)
			(stroke
				(width 0.1524)
				(type default)
			)
			(layer "F.SilkS")
		)
		(fp_line
			(start 1.239774 1.495298)
			(end -1.239774 1.495298)
			(stroke
				(width 0.1524)
				(type default)
			)
			(layer "F.SilkS")
		)
		(fp_line
			(start -1.239774 1.495298)
			(end -1.239774 -1.495298)
			(stroke
				(width 0.1524)
				(type default)
			)
			(layer "F.SilkS")
		)
		(fp_poly
			(pts
				(xy -1.809242 -1.849628) (xy -2.527808 -1.131316) (xy -1.450086 -0.77216)
			)
			(stroke
				(width 0)
				(type default)
			)
			(fill yes)
			(layer "F.SilkS")
		)
		(fp_line
			(start 0.8001 -1.050036)
			(end 0.8001 1.050036)
			(stroke
				(width 0.1)
				(type default)
			)
			(layer "F.Fab")
		)
		(fp_line
			(start -0.8001 -1.050036)
			(end 0.8001 -1.050036)
			(stroke
				(width 0.1)
				(type default)
			)
			(layer "F.Fab")
		)
		(fp_line
			(start 0.8001 1.050036)
			(end -0.8001 1.050036)
			(stroke
				(width 0.1)
				(type default)
			)
			(layer "F.Fab")
		)
		(fp_line
			(start -0.8001 1.050036)
			(end -0.8001 -1.050036)
			(stroke
				(width 0.1)
				(type default)
			)
			(layer "F.Fab")
		)
		(fp_poly
			(pts
				(xy -2.458974 -0.508) (xy -2.458974 0.508) (xy -1.442974 0)
			)
			(stroke
				(width 0)
				(type default)
			)
			(fill yes)
			(layer "F.Fab")
		)
		(pad "1_2" smd circle
			(at -0.374904 0 180)
			(size 0 0)
			(layers "F.Cu" "F.Mask" "F.Paste")
			(net "P3V3_AUX")
		)
		(pad "3" smd rect
			(at -0.499872 0.999998 90)
			(size 0.254 0.7112)
			(layers "F.Cu" "F.Mask" "F.Paste")
			(net "GND")
		)
		(pad "4" smd rect
			(at 0 0.999998 90)
			(size 0.254 0.7112)
			(layers "F.Cu" "F.Mask" "F.Paste")
			(net "P3V3_NIC7_CO_ILIMIT")
		)
		(pad "5" smd rect
			(at 0.499872 0.999998 90)
			(size 0.254 0.7112)
			(layers "F.Cu" "F.Mask" "F.Paste")
			(net "P3V3_NIC7_CO_MODE")
		)
		(pad "6_7" smd circle
			(at 0.374904 0)
			(size 0 0)
			(layers "F.Cu" "F.Mask" "F.Paste")
			(net "P3V3_NIC7")
		)
		(pad "8" smd rect
			(at 0.499872 -0.999998 90)
			(size 0.254 0.7112)
			(layers "F.Cu" "F.Mask" "F.Paste")
			(net "P3V3_NIC7_CO_GATE")
		)
		(pad "9" smd rect
			(at 0 -0.999998 90)
			(size 0.254 0.7112)
			(layers "F.Cu" "F.Mask" "F.Paste")
			(net "P3V3_NIC7_CO_EN")
		)
		(pad "10" smd rect
			(at -0.499872 -0.999998 90)
			(size 0.254 0.7112)
			(layers "F.Cu" "F.Mask" "F.Paste")
			(net "P3V3_NIC7_CO_DV_DT")
		)
	)
	(footprint ""
		(layer "F.Cu")
		(at 119.983758 -61.487812 180)
		(property "Reference" "R5974"
			(at 0 0 180)
			(layer "F.SilkS")
			(hide yes)
			(effects
				(font
					(size 1.27 1.27)
				)
			)
		)
		(property "Value" ""
			(at 0 0 180)
			(layer "F.Fab")
			(effects
				(font
					(size 1.27 1.27)
				)
			)
		)
		(duplicate_pad_numbers_are_jumpers no)
		(fp_line
			(start 0.7874 0.4064)
			(end -0.7874 0.4064)
			(stroke
				(width 0.1524)
				(type default)
			)
			(layer "F.SilkS")
		)
		(fp_line
			(start 0.7874 -0.4064)
			(end 0.7874 0.4064)
			(stroke
				(width 0.1524)
				(type default)
			)
			(layer "F.SilkS")
		)
		(fp_line
			(start -0.7874 0.4064)
			(end -0.7874 -0.4064)
			(stroke
				(width 0.1524)
				(type default)
			)
			(layer "F.SilkS")
		)
		(fp_line
			(start -0.7874 -0.4064)
			(end 0.7874 -0.4064)
			(stroke
				(width 0.1524)
				(type default)
			)
			(layer "F.SilkS")
		)
		(fp_line
			(start 0.67945 0.3048)
			(end 0.120396 0.3048)
			(stroke
				(width 0.1)
				(type default)
			)
			(layer "F.Fab")
		)
		(fp_line
			(start 0.67945 -0.3048)
			(end 0.67945 0.3048)
			(stroke
				(width 0.1)
				(type default)
			)
			(layer "F.Fab")
		)
		(fp_line
			(start 0.12065 -0.2794)
			(end 0.12065 -0.3048)
			(stroke
				(width 0.1)
				(type default)
			)
			(layer "F.Fab")
		)
		(fp_line
			(start 0.12065 -0.3048)
			(end 0.67945 -0.3048)
			(stroke
				(width 0.1)
				(type default)
			)
			(layer "F.Fab")
		)
		(fp_line
			(start 0.120396 0.3048)
			(end 0.120396 0.2794)
			(stroke
				(width 0.1)
				(type default)
			)
			(layer "F.Fab")
		)
		(fp_line
			(start 0.120396 0.2794)
			(end -0.12065 0.2794)
			(stroke
				(width 0.1)
				(type default)
			)
			(layer "F.Fab")
		)
		(fp_line
			(start -0.12065 0.3048)
			(end -0.67945 0.3048)
			(stroke
				(width 0.1)
				(type default)
			)
			(layer "F.Fab")
		)
		(fp_line
			(start -0.12065 0.2794)
			(end -0.12065 0.3048)
			(stroke
				(width 0.1)
				(type default)
			)
			(layer "F.Fab")
		)
		(fp_line
			(start -0.12065 -0.2794)
			(end 0.12065 -0.2794)
			(stroke
				(width 0.1)
				(type default)
			)
			(layer "F.Fab")
		)
		(fp_line
			(start -0.12065 -0.305054)
			(end -0.12065 -0.2794)
			(stroke
				(width 0.1)
				(type default)
			)
			(layer "F.Fab")
		)
		(fp_line
			(start -0.67945 0.3048)
			(end -0.67945 -0.305054)
			(stroke
				(width 0.1)
				(type default)
			)
			(layer "F.Fab")
		)
		(fp_line
			(start -0.67945 -0.305054)
			(end -0.12065 -0.305054)
			(stroke
				(width 0.1)
				(type default)
			)
			(layer "F.Fab")
		)
		(pad "1" smd circle
			(at -0.40005 0 180)
			(size 0 0)
			(layers "F.Cu" "F.Mask" "F.Paste")
			(net "PWRGD_P12V_SSD4_D")
		)
		(pad "2" smd circle
			(at 0.40005 0 180)
			(size 0 0)
			(layers "F.Cu" "F.Mask" "F.Paste")
			(net "PWRGD_P12V_SSD4_R")
		)
	)
	(footprint ""
		(layer "F.Cu")
		(at 245.732808 -309.555642)
		(property "Reference" "PC260"
			(at 0 0 0)
			(layer "F.SilkS")
			(hide yes)
			(effects
				(font
					(size 1.27 1.27)
				)
			)
		)
		(property "Value" ""
			(at 0 0 0)
			(layer "F.Fab")
			(effects
				(font
					(size 1.27 1.27)
				)
			)
		)
		(duplicate_pad_numbers_are_jumpers no)
		(fp_line
			(start -0.7874 -0.4064)
			(end 0.7874 -0.4064)
			(stroke
				(width 0.1524)
				(type default)
			)
			(layer "F.SilkS")
		)
		(fp_line
			(start -0.7874 0.4064)
			(end -0.7874 -0.4064)
			(stroke
				(width 0.1524)
				(type default)
			)
			(layer "F.SilkS")
		)
		(fp_line
			(start 0.7874 -0.4064)
			(end 0.7874 0.4064)
			(stroke
				(width 0.1524)
				(type default)
			)
			(layer "F.SilkS")
		)
		(fp_line
			(start 0.7874 0.4064)
			(end -0.7874 0.4064)
			(stroke
				(width 0.1524)
				(type default)
			)
			(layer "F.SilkS")
		)
		(fp_line
			(start -0.67945 -0.305054)
			(end -0.12065 -0.305054)
			(stroke
				(width 0.1)
				(type default)
			)
			(layer "F.Fab")
		)
		(fp_line
			(start -0.67945 0.3048)
			(end -0.67945 -0.305054)
			(stroke
				(width 0.1)
				(type default)
			)
			(layer "F.Fab")
		)
		(fp_line
			(start -0.12065 -0.305054)
			(end -0.12065 -0.2794)
			(stroke
				(width 0.1)
				(type default)
			)
			(layer "F.Fab")
		)
		(fp_line
			(start -0.12065 -0.2794)
			(end 0.12065 -0.2794)
			(stroke
				(width 0.1)
				(type default)
			)
			(layer "F.Fab")
		)
		(fp_line
			(start -0.12065 0.2794)
			(end -0.12065 0.3048)
			(stroke
				(width 0.1)
				(type default)
			)
			(layer "F.Fab")
		)
		(fp_line
			(start -0.12065 0.3048)
			(end -0.67945 0.3048)
			(stroke
				(width 0.1)
				(type default)
			)
			(layer "F.Fab")
		)
		(fp_line
			(start 0.120396 0.2794)
			(end -0.12065 0.2794)
			(stroke
				(width 0.1)
				(type default)
			)
			(layer "F.Fab")
		)
		(fp_line
			(start 0.120396 0.3048)
			(end 0.120396 0.2794)
			(stroke
				(width 0.1)
				(type default)
			)
			(layer "F.Fab")
		)
		(fp_line
			(start 0.12065 -0.3048)
			(end 0.67945 -0.3048)
			(stroke
				(width 0.1)
				(type default)
			)
			(layer "F.Fab")
		)
		(fp_line
			(start 0.12065 -0.2794)
			(end 0.12065 -0.3048)
			(stroke
				(width 0.1)
				(type default)
			)
			(layer "F.Fab")
		)
		(fp_line
			(start 0.67945 -0.3048)
			(end 0.67945 0.3048)
			(stroke
				(width 0.1)
				(type default)
			)
			(layer "F.Fab")
		)
		(fp_line
			(start 0.67945 0.3048)
			(end 0.120396 0.3048)
			(stroke
				(width 0.1)
				(type default)
			)
			(layer "F.Fab")
		)
		(pad "1" smd circle
			(at -0.40005 0)
			(size 0 0)
			(layers "F.Cu" "F.Mask" "F.Paste")
			(net "P1V25_PEX2_FB")
		)
		(pad "2" smd circle
			(at 0.40005 0)
			(size 0 0)
			(layers "F.Cu" "F.Mask" "F.Paste")
			(net "SH_P1V25_PEX2_FB_P")
		)
	)
)
